# BASEBOARD_FAB2 (Tioga Pass) — schematic netlist excerpt (pin names and nets, part order shuffled) for the footprints in the layout excerpt that follows; sources: Cadence DE-HDL packaged netlist, KiCad conversion of Wiwynn_Tioga_Pass_MB.brd

C4M4  CAP  10UF 4V 20% X6S  pkg 0603LF  page 232 : A = PVPP_DEF ; B = GND
C6M1  CAP_A  0.01UF 25V 10% X7R  pkg 0402V  page 50 : A = M_D_VREF ; B = GND
R2L21  RES  2.0K 1% CHIP  pkg 0402  page 173 : A = P3V3 ; B = PU_DATAIN1_SATA_0_R

(kicad_pcb
	(version 20260206)
	(generator "pcbnew")
	(generator_version "10.0")
	(general
		(thickness 1.6)
		(legacy_teardrops no)
	)
	(paper "A4")
	(title_block
		(title "Wiwynn_Tioga_Pass_MB.brd")
		(comment 1 "Tioga Pass / footprints 4354-4356 of 4770")
	)
	(layers
		(0 "F.Cu" signal "TOP")
		(4 "In1.Cu" signal "L2GND")
		(6 "In2.Cu" signal "L3")
		(8 "In3.Cu" signal "L4GND")
		(10 "In4.Cu" signal "L5")
		(12 "In5.Cu" signal "L6GND")
		(14 "In6.Cu" signal "L7VCC")
		(16 "In7.Cu" signal "L8VCC")
		(18 "In8.Cu" signal "L9GND")
		(20 "In9.Cu" signal "L10")
		(22 "In10.Cu" signal "L11GND")
		(24 "In11.Cu" signal "L12")
		(26 "In12.Cu" signal "L13GND")
		(2 "B.Cu" signal "BOTTOM")
		(9 "F.Adhes" user "F.Adhesive")
		(11 "B.Adhes" user "B.Adhesive")
		(13 "F.Paste" user "Package Geometry/Pastemask Top")
		(15 "B.Paste" user "Package Geometry/Pastemask Bottom")
		(5 "F.SilkS" user "Ref Des/Silkscreen Top")
		(7 "B.SilkS" user "Ref Des/Silkscreen Bottom")
		(1 "F.Mask" user "Board Geometry/Soldermask Top")
		(3 "B.Mask" user "Board Geometry/Soldermask Bottom")
		(17 "Dwgs.User" user "User.Drawings")
		(19 "Cmts.User" user "User.Comments")
		(21 "Eco1.User" user "User.Eco1")
		(23 "Eco2.User" user "User.Eco2")
		(25 "Edge.Cuts" user "Board Geometry/Outline")
		(27 "Margin" user)
		(31 "F.CrtYd" user "Package Geometry/Place Bound Top")
		(29 "B.CrtYd" user "Package Geometry/Place Bound Bottom")
		(35 "F.Fab" user "Ref Des/Assembly Top")
		(33 "B.Fab" user "Ref Des/Assembly Bottom")
	)
	(footprint ""
		(layer "B.Cu")
		(at 318.543432 -135.382 -90)
		(property "Reference" "C4M4"
			(at 0 0 90)
			(layer "B.SilkS")
			(hide yes)
			(effects
				(font
					(size 1.27 1.27)
				)
				(justify mirror)
			)
		)
		(property "Value" ""
			(at 0 0 90)
			(layer "B.Fab")
			(effects
				(font
					(size 1.27 1.27)
				)
				(justify mirror)
			)
		)
		(duplicate_pad_numbers_are_jumpers no)
		(fp_poly
			(pts
				(xy 0.4953 -0.2032) (xy -0.4953 -0.2032) (xy -0.4953 1.6002) (xy 0.4953 1.6002)
			)
			(stroke
				(width 0)
				(type default)
			)
			(fill no)
			(layer "B.CrtYd")
		)
		(fp_line
			(start -0.4953 1.6002)
			(end 0.4953 1.6002)
			(stroke
				(width 0.1)
				(type default)
			)
			(layer "B.Fab")
		)
		(fp_line
			(start 0.4953 1.6002)
			(end 0.4953 -0.2032)
			(stroke
				(width 0.1)
				(type default)
			)
			(layer "B.Fab")
		)
		(fp_line
			(start -0.4953 -0.2032)
			(end -0.4953 1.6002)
			(stroke
				(width 0.1)
				(type default)
			)
			(layer "B.Fab")
		)
		(fp_line
			(start 0.4953 -0.2032)
			(end -0.4953 -0.2032)
			(stroke
				(width 0.1)
				(type default)
			)
			(layer "B.Fab")
		)
		(pad "1" smd rect
			(at 0 0 90)
			(size 0.762 0.889)
			(layers "B.Cu" "B.Mask" "B.Paste")
			(net "PVPP_DEF")
		)
		(pad "2" smd rect
			(at 0 1.397 90)
			(size 0.762 0.889)
			(layers "B.Cu" "B.Mask" "B.Paste")
			(net "GND")
		)
		(zone
			(layer "B.Cu")
			(hatch none 0.5)
			(connect_pads
				(clearance 0)
			)
			(min_thickness 0.25)
			(keepout
				(tracks not_allowed)
				(vias allowed)
				(pads allowed)
				(copperpour not_allowed)
				(footprints allowed)
			)
			(placement
				(enabled no)
				(sheetname "")
			)
			(fill
				(thermal_gap 0.5)
				(thermal_bridge_width 0.5)
				(island_removal_mode 0)
			)
			(polygon
				(pts
					(xy 318.098932 -135.001) (xy 318.098932 -135.763) (xy 317.590932 -135.763) (xy 317.590932 -135.001)
				)
			)
		)
	)
	(footprint ""
		(layer "B.Cu")
		(at 195.5546 -135.3312 90)
		(property "Reference" "C6M1"
			(at 0 0 90)
			(layer "B.SilkS")
			(hide yes)
			(effects
				(font
					(size 1.27 1.27)
				)
				(justify mirror)
			)
		)
		(property "Value" ""
			(at 0 0 90)
			(layer "B.Fab")
			(effects
				(font
					(size 1.27 1.27)
				)
				(justify mirror)
			)
		)
		(duplicate_pad_numbers_are_jumpers no)
		(fp_poly
			(pts
				(xy -0.3048 -0.1016) (xy -0.3048 0.9906) (xy 0.3048 0.9906) (xy 0.3048 -0.1016)
			)
			(stroke
				(width 0)
				(type default)
			)
			(fill no)
			(layer "B.CrtYd")
		)
		(fp_line
			(start 0.3048 -0.1016)
			(end 0.3048 0.9906)
			(stroke
				(width 0.1)
				(type default)
			)
			(layer "B.Fab")
		)
		(fp_line
			(start -0.3048 -0.1016)
			(end 0.3048 -0.1016)
			(stroke
				(width 0.1)
				(type default)
			)
			(layer "B.Fab")
		)
		(fp_line
			(start 0.3048 0.9906)
			(end -0.3048 0.9906)
			(stroke
				(width 0.1)
				(type default)
			)
			(layer "B.Fab")
		)
		(fp_line
			(start -0.3048 0.9906)
			(end -0.3048 -0.1016)
			(stroke
				(width 0.1)
				(type default)
			)
			(layer "B.Fab")
		)
		(pad "1" smd rect
			(at 0 0 270)
			(size 0.508 0.508)
			(layers "B.Cu" "B.Mask" "B.Paste")
			(net "M_D_VREF")
		)
		(pad "2" smd rect
			(at 0 0.889 270)
			(size 0.508 0.508)
			(layers "B.Cu" "B.Mask" "B.Paste")
			(net "GND")
		)
		(zone
			(layer "B.Cu")
			(hatch none 0.5)
			(connect_pads
				(clearance 0)
			)
			(min_thickness 0.25)
			(keepout
				(tracks allowed)
				(vias not_allowed)
				(pads allowed)
				(copperpour not_allowed)
				(footprints allowed)
			)
			(placement
				(enabled no)
				(sheetname "")
			)
			(fill
				(thermal_gap 0.5)
				(thermal_bridge_width 0.5)
				(island_removal_mode 0)
			)
			(polygon
				(pts
					(xy 195.8086 -135.5852) (xy 195.8086 -135.0772) (xy 196.1896 -135.0772) (xy 196.1896 -135.5852)
				)
			)
		)
		(zone
			(layer "B.Cu")
			(hatch none 0.5)
			(connect_pads
				(clearance 0)
			)
			(min_thickness 0.25)
			(keepout
				(tracks not_allowed)
				(vias allowed)
				(pads allowed)
				(copperpour not_allowed)
				(footprints allowed)
			)
			(placement
				(enabled no)
				(sheetname "")
			)
			(fill
				(thermal_gap 0.5)
				(thermal_bridge_width 0.5)
				(island_removal_mode 0)
			)
			(polygon
				(pts
					(xy 196.1896 -135.5852) (xy 196.1896 -135.0772) (xy 195.8086 -135.0772) (xy 195.8086 -135.5852)
				)
			)
		)
	)
	(footprint ""
		(layer "B.Cu")
		(at 434.132482 -147.504658 -90)
		(property "Reference" "R2L21"
			(at 0 0 90)
			(layer "B.SilkS")
			(hide yes)
			(effects
				(font
					(size 1.27 1.27)
				)
				(justify mirror)
			)
		)
		(property "Value" ""
			(at 0 0 90)
			(layer "B.Fab")
			(effects
				(font
					(size 1.27 1.27)
				)
				(justify mirror)
			)
		)
		(duplicate_pad_numbers_are_jumpers no)
		(fp_poly
			(pts
				(xy 0.2794 -0.1016) (xy -0.2794 -0.1016) (xy -0.2794 0.9906) (xy 0.2794 0.9906)
			)
			(stroke
				(width 0)
				(type default)
			)
			(fill no)
			(layer "B.CrtYd")
		)
		(fp_line
			(start -0.2794 0.9906)
			(end -0.2794 -0.1016)
			(stroke
				(width 0.1)
				(type default)
			)
			(layer "B.Fab")
		)
		(fp_line
			(start 0.2794 0.9906)
			(end -0.2794 0.9906)
			(stroke
				(width 0.1)
				(type default)
			)
			(layer "B.Fab")
		)
		(fp_line
			(start -0.2794 -0.1016)
			(end 0.2794 -0.1016)
			(stroke
				(width 0.1)
				(type default)
			)
			(layer "B.Fab")
		)
		(fp_line
			(start 0.2794 -0.1016)
			(end 0.2794 0.9906)
			(stroke
				(width 0.1)
				(type default)
			)
			(layer "B.Fab")
		)
		(pad "1" smd rect
			(at 0 0 90)
			(size 0.508 0.508)
			(layers "B.Cu" "B.Mask" "B.Paste")
			(net "P3V3")
		)
		(pad "2" smd rect
			(at 0 0.889 90)
			(size 0.508 0.508)
			(layers "B.Cu" "B.Mask" "B.Paste")
			(net "PU_DATAIN1_SATA_0_R")
		)
		(zone
			(layer "B.Cu")
			(hatch none 0.5)
			(connect_pads
				(clearance 0)
			)
			(min_thickness 0.25)
			(keepout
				(tracks not_allowed)
				(vias allowed)
				(pads allowed)
				(copperpour not_allowed)
				(footprints allowed)
			)
			(placement
				(enabled no)
				(sheetname "")
			)
			(fill
				(thermal_gap 0.5)
				(thermal_bridge_width 0.5)
				(island_removal_mode 0)
			)
			(polygon
				(pts
					(xy 433.497482 -147.250658) (xy 433.497482 -147.758658) (xy 433.878482 -147.758658) (xy 433.878482 -147.250658)
				)
			)
		)
		(zone
			(layer "B.Cu")
			(hatch none 0.5)
			(connect_pads
				(clearance 0)
			)
			(min_thickness 0.25)
			(keepout
				(tracks allowed)
				(vias not_allowed)
				(pads allowed)
				(copperpour not_allowed)
				(footprints allowed)
			)
			(placement
				(enabled no)
				(sheetname "")
			)
			(fill
				(thermal_gap 0.5)
				(thermal_bridge_width 0.5)
				(island_removal_mode 0)
			)
			(polygon
				(pts
					(xy 433.878482 -147.250658) (xy 433.878482 -147.758658) (xy 433.497482 -147.758658) (xy 433.497482 -147.250658)
				)
			)
		)
	)
)
